(kicad_pcb
	(version 20260206)
	(generator "pcbnew")
	(generator_version "10.0")
	(general
		(thickness 1.6)
		(legacy_teardrops no)
	)
	(paper "A4")
	(title_block
		(title "9052_F0T_PDB_Converter_Brick_F_V03_1208_1600_OCP.brd")
		(comment 1 "Grand Teton / footprints 475-480 of 578")
	)
	(layers
		(0 "F.Cu" signal "TOP")
		(4 "In1.Cu" signal "GND")
		(6 "In2.Cu" signal "IN1")
		(8 "In3.Cu" signal "GND1")
		(10 "In4.Cu" signal "VCC")
		(12 "In5.Cu" signal "VCC1")
		(14 "In6.Cu" signal "GND2")
		(16 "In7.Cu" signal "IN2")
		(18 "In8.Cu" signal "GND3")
		(2 "B.Cu" signal "BOTTOM")
		(9 "F.Adhes" user "F.Adhesive")
		(11 "B.Adhes" user "B.Adhesive")
		(13 "F.Paste" user "Package Geometry/Pastemask Top")
		(15 "B.Paste" user "Package Geometry/Pastemask Bottom")
		(5 "F.SilkS" user "Ref Des/Silkscreen Top")
		(7 "B.SilkS" user "Ref Des/Silkscreen Bottom")
		(1 "F.Mask" user "Board Geometry/Soldermask Top")
		(3 "B.Mask" user "Board Geometry/Soldermask Bottom")
		(17 "Dwgs.User" user "User.Drawings")
		(19 "Cmts.User" user "User.Comments")
		(21 "Eco1.User" user "User.Eco1")
		(23 "Eco2.User" user "User.Eco2")
		(25 "Edge.Cuts" user "Board Geometry/Outline")
		(27 "Margin" user)
		(31 "F.CrtYd" user "Package Geometry/Place Bound Top")
		(29 "B.CrtYd" user "Package Geometry/Place Bound Bottom")
		(35 "F.Fab" user "Ref Des/Assembly Top")
		(33 "B.Fab" user "Ref Des/Assembly Bottom")
	)
	(footprint ""
		(layer "B.Cu")
		(at 54.483 -77.47 180)
		(property "Reference" "C61"
			(at 0 0 0)
			(layer "B.SilkS")
			(hide yes)
			(effects
				(font
					(size 1.27 1.27)
				)
				(justify mirror)
			)
		)
		(property "Value" ""
			(at 0 0 0)
			(layer "B.Fab")
			(effects
				(font
					(size 1.27 1.27)
				)
				(justify mirror)
			)
		)
		(duplicate_pad_numbers_are_jumpers no)
		(fp_line
			(start 0.7874 0.4064)
			(end 0.7874 -0.4064)
			(stroke
				(width 0.1524)
				(type default)
			)
			(layer "B.SilkS")
		)
		(fp_line
			(start 0.7874 -0.4064)
			(end -0.7874 -0.4064)
			(stroke
				(width 0.1524)
				(type default)
			)
			(layer "B.SilkS")
		)
		(fp_line
			(start -0.7874 0.4064)
			(end 0.7874 0.4064)
			(stroke
				(width 0.1524)
				(type default)
			)
			(layer "B.SilkS")
		)
		(fp_line
			(start -0.7874 -0.4064)
			(end -0.7874 0.4064)
			(stroke
				(width 0.1524)
				(type default)
			)
			(layer "B.SilkS")
		)
		(fp_line
			(start 0.67945 0.3048)
			(end 0.67945 -0.305054)
			(stroke
				(width 0.1)
				(type default)
			)
			(layer "B.Fab")
		)
		(fp_line
			(start 0.67945 -0.305054)
			(end 0.12065 -0.305054)
			(stroke
				(width 0.1)
				(type default)
			)
			(layer "B.Fab")
		)
		(fp_line
			(start 0.12065 0.3048)
			(end 0.67945 0.3048)
			(stroke
				(width 0.1)
				(type default)
			)
			(layer "B.Fab")
		)
		(fp_line
			(start 0.12065 0.2794)
			(end 0.12065 0.3048)
			(stroke
				(width 0.1)
				(type default)
			)
			(layer "B.Fab")
		)
		(fp_line
			(start 0.12065 -0.2794)
			(end -0.12065 -0.2794)
			(stroke
				(width 0.1)
				(type default)
			)
			(layer "B.Fab")
		)
		(fp_line
			(start 0.12065 -0.305054)
			(end 0.12065 -0.2794)
			(stroke
				(width 0.1)
				(type default)
			)
			(layer "B.Fab")
		)
		(fp_line
			(start -0.120396 0.3048)
			(end -0.120396 0.2794)
			(stroke
				(width 0.1)
				(type default)
			)
			(layer "B.Fab")
		)
		(fp_line
			(start -0.120396 0.2794)
			(end 0.12065 0.2794)
			(stroke
				(width 0.1)
				(type default)
			)
			(layer "B.Fab")
		)
		(fp_line
			(start -0.12065 -0.2794)
			(end -0.12065 -0.3048)
			(stroke
				(width 0.1)
				(type default)
			)
			(layer "B.Fab")
		)
		(fp_line
			(start -0.12065 -0.3048)
			(end -0.67945 -0.3048)
			(stroke
				(width 0.1)
				(type default)
			)
			(layer "B.Fab")
		)
		(fp_line
			(start -0.67945 0.3048)
			(end -0.120396 0.3048)
			(stroke
				(width 0.1)
				(type default)
			)
			(layer "B.Fab")
		)
		(fp_line
			(start -0.67945 -0.3048)
			(end -0.67945 0.3048)
			(stroke
				(width 0.1)
				(type default)
			)
			(layer "B.Fab")
		)
		(pad "1" smd circle
			(at 0.40005 0)
			(size 0 0)
			(layers "B.Cu" "B.Mask" "B.Paste")
			(net "SMB_P52V_VPDB_SDA")
		)
		(pad "2" smd circle
			(at -0.40005 0)
			(size 0 0)
			(layers "B.Cu" "B.Mask" "B.Paste")
			(net "GND")
		)
	)
	(footprint ""
		(layer "B.Cu")
		(at 289.687 -53.34 90)
		(property "Reference" "PR3"
			(at 0 0 90)
			(layer "B.SilkS")
			(hide yes)
			(effects
				(font
					(size 1.27 1.27)
				)
				(justify mirror)
			)
		)
		(property "Value" ""
			(at 0 0 90)
			(layer "B.Fab")
			(effects
				(font
					(size 1.27 1.27)
				)
				(justify mirror)
			)
		)
		(duplicate_pad_numbers_are_jumpers no)
		(fp_line
			(start 1.651 -0.8382)
			(end -1.651 -0.8382)
			(stroke
				(width 0.1524)
				(type default)
			)
			(layer "B.SilkS")
		)
		(fp_line
			(start -1.651 -0.8382)
			(end -1.651 0.8382)
			(stroke
				(width 0.1524)
				(type default)
			)
			(layer "B.SilkS")
		)
		(fp_line
			(start 1.651 0.8382)
			(end 1.651 -0.8382)
			(stroke
				(width 0.1524)
				(type default)
			)
			(layer "B.SilkS")
		)
		(fp_line
			(start -1.651 0.8382)
			(end 1.651 0.8382)
			(stroke
				(width 0.1524)
				(type default)
			)
			(layer "B.SilkS")
		)
		(fp_line
			(start 1.559814 -0.7366)
			(end 1.559814 0.7366)
			(stroke
				(width 0.1)
				(type default)
			)
			(layer "B.Fab")
		)
		(fp_line
			(start 1.524 -0.7366)
			(end 1.559814 -0.7366)
			(stroke
				(width 0.1)
				(type default)
			)
			(layer "B.Fab")
		)
		(fp_line
			(start -1.524 -0.7366)
			(end 1.524 -0.7366)
			(stroke
				(width 0.1)
				(type default)
			)
			(layer "B.Fab")
		)
		(fp_line
			(start -1.560576 -0.7366)
			(end -1.524 -0.7366)
			(stroke
				(width 0.1)
				(type default)
			)
			(layer "B.Fab")
		)
		(fp_line
			(start 1.559814 0.7366)
			(end 1.524 0.7366)
			(stroke
				(width 0.1)
				(type default)
			)
			(layer "B.Fab")
		)
		(fp_line
			(start 1.524 0.7366)
			(end -1.524 0.7366)
			(stroke
				(width 0.1)
				(type default)
			)
			(layer "B.Fab")
		)
		(fp_line
			(start -1.524 0.7366)
			(end -1.560576 0.7366)
			(stroke
				(width 0.1)
				(type default)
			)
			(layer "B.Fab")
		)
		(fp_line
			(start -1.560576 0.7366)
			(end -1.560576 -0.7366)
			(stroke
				(width 0.1)
				(type default)
			)
			(layer "B.Fab")
		)
		(pad "1" smd rect
			(at 0.94996 0 90)
			(size 1.1176 1.3716)
			(layers "B.Cu" "B.Mask" "B.Paste")
			(net "P52V_1")
		)
		(pad "2" smd rect
			(at -0.94996 0 90)
			(size 1.1176 1.3716)
			(layers "B.Cu" "B.Mask" "B.Paste")
			(net "P52V_HS1_UVLO_EN")
		)
	)
	(footprint ""
		(layer "B.Cu")
		(at 289.38093 -36.508436 180)
		(property "Reference" "R5919"
			(at 0 0 0)
			(layer "B.SilkS")
			(hide yes)
			(effects
				(font
					(size 1.27 1.27)
				)
				(justify mirror)
			)
		)
		(property "Value" ""
			(at 0 0 0)
			(layer "B.Fab")
			(effects
				(font
					(size 1.27 1.27)
				)
				(justify mirror)
			)
		)
		(duplicate_pad_numbers_are_jumpers no)
		(fp_line
			(start 0.7874 0.4064)
			(end 0.7874 -0.4064)
			(stroke
				(width 0.1524)
				(type default)
			)
			(layer "B.SilkS")
		)
		(fp_line
			(start 0.7874 -0.4064)
			(end -0.7874 -0.4064)
			(stroke
				(width 0.1524)
				(type default)
			)
			(layer "B.SilkS")
		)
		(fp_line
			(start -0.7874 0.4064)
			(end 0.7874 0.4064)
			(stroke
				(width 0.1524)
				(type default)
			)
			(layer "B.SilkS")
		)
		(fp_line
			(start -0.7874 -0.4064)
			(end -0.7874 0.4064)
			(stroke
				(width 0.1524)
				(type default)
			)
			(layer "B.SilkS")
		)
		(fp_line
			(start 0.67945 0.3048)
			(end 0.67945 -0.305054)
			(stroke
				(width 0.1)
				(type default)
			)
			(layer "B.Fab")
		)
		(fp_line
			(start 0.67945 -0.305054)
			(end 0.12065 -0.305054)
			(stroke
				(width 0.1)
				(type default)
			)
			(layer "B.Fab")
		)
		(fp_line
			(start 0.12065 0.3048)
			(end 0.67945 0.3048)
			(stroke
				(width 0.1)
				(type default)
			)
			(layer "B.Fab")
		)
		(fp_line
			(start 0.12065 0.2794)
			(end 0.12065 0.3048)
			(stroke
				(width 0.1)
				(type default)
			)
			(layer "B.Fab")
		)
		(fp_line
			(start 0.12065 -0.2794)
			(end -0.12065 -0.2794)
			(stroke
				(width 0.1)
				(type default)
			)
			(layer "B.Fab")
		)
		(fp_line
			(start 0.12065 -0.305054)
			(end 0.12065 -0.2794)
			(stroke
				(width 0.1)
				(type default)
			)
			(layer "B.Fab")
		)
		(fp_line
			(start -0.120396 0.3048)
			(end -0.120396 0.2794)
			(stroke
				(width 0.1)
				(type default)
			)
			(layer "B.Fab")
		)
		(fp_line
			(start -0.120396 0.2794)
			(end 0.12065 0.2794)
			(stroke
				(width 0.1)
				(type default)
			)
			(layer "B.Fab")
		)
		(fp_line
			(start -0.12065 -0.2794)
			(end -0.12065 -0.3048)
			(stroke
				(width 0.1)
				(type default)
			)
			(layer "B.Fab")
		)
		(fp_line
			(start -0.12065 -0.3048)
			(end -0.67945 -0.3048)
			(stroke
				(width 0.1)
				(type default)
			)
			(layer "B.Fab")
		)
		(fp_line
			(start -0.67945 0.3048)
			(end -0.120396 0.3048)
			(stroke
				(width 0.1)
				(type default)
			)
			(layer "B.Fab")
		)
		(fp_line
			(start -0.67945 -0.3048)
			(end -0.67945 0.3048)
			(stroke
				(width 0.1)
				(type default)
			)
			(layer "B.Fab")
		)
		(pad "1" smd circle
			(at 0.40005 0)
			(size 0 0)
			(layers "B.Cu" "B.Mask" "B.Paste")
			(net "FM_AC_PWR_CYCLE_N")
		)
		(pad "2" smd circle
			(at -0.40005 0)
			(size 0 0)
			(layers "B.Cu" "B.Mask" "B.Paste")
			(net "FM_AC_PWR_CYCLE_R1_N")
		)
	)
	(footprint ""
		(layer "B.Cu")
		(at 176.850294 -114.046 90)
		(property "Reference" "C70"
			(at 0 0 90)
			(layer "B.SilkS")
			(hide yes)
			(effects
				(font
					(size 1.27 1.27)
				)
				(justify mirror)
			)
		)
		(property "Value" ""
			(at 0 0 90)
			(layer "B.Fab")
			(effects
				(font
					(size 1.27 1.27)
				)
				(justify mirror)
			)
		)
		(duplicate_pad_numbers_are_jumpers no)
		(fp_line
			(start 0.7874 -0.4064)
			(end -0.7874 -0.4064)
			(stroke
				(width 0.1524)
				(type default)
			)
			(layer "B.SilkS")
		)
		(fp_line
			(start -0.7874 -0.4064)
			(end -0.7874 0.4064)
			(stroke
				(width 0.1524)
				(type default)
			)
			(layer "B.SilkS")
		)
		(fp_line
			(start 0.7874 0.4064)
			(end 0.7874 -0.4064)
			(stroke
				(width 0.1524)
				(type default)
			)
			(layer "B.SilkS")
		)
		(fp_line
			(start -0.7874 0.4064)
			(end 0.7874 0.4064)
			(stroke
				(width 0.1524)
				(type default)
			)
			(layer "B.SilkS")
		)
		(fp_line
			(start 0.67945 -0.305054)
			(end 0.12065 -0.305054)
			(stroke
				(width 0.1)
				(type default)
			)
			(layer "B.Fab")
		)
		(fp_line
			(start 0.12065 -0.305054)
			(end 0.12065 -0.2794)
			(stroke
				(width 0.1)
				(type default)
			)
			(layer "B.Fab")
		)
		(fp_line
			(start -0.12065 -0.3048)
			(end -0.67945 -0.3048)
			(stroke
				(width 0.1)
				(type default)
			)
			(layer "B.Fab")
		)
		(fp_line
			(start -0.67945 -0.3048)
			(end -0.67945 0.3048)
			(stroke
				(width 0.1)
				(type default)
			)
			(layer "B.Fab")
		)
		(fp_line
			(start 0.12065 -0.2794)
			(end -0.12065 -0.2794)
			(stroke
				(width 0.1)
				(type default)
			)
			(layer "B.Fab")
		)
		(fp_line
			(start -0.12065 -0.2794)
			(end -0.12065 -0.3048)
			(stroke
				(width 0.1)
				(type default)
			)
			(layer "B.Fab")
		)
		(fp_line
			(start 0.12065 0.2794)
			(end 0.12065 0.3048)
			(stroke
				(width 0.1)
				(type default)
			)
			(layer "B.Fab")
		)
		(fp_line
			(start -0.120396 0.2794)
			(end 0.12065 0.2794)
			(stroke
				(width 0.1)
				(type default)
			)
			(layer "B.Fab")
		)
		(fp_line
			(start 0.67945 0.3048)
			(end 0.67945 -0.305054)
			(stroke
				(width 0.1)
				(type default)
			)
			(layer "B.Fab")
		)
		(fp_line
			(start 0.12065 0.3048)
			(end 0.67945 0.3048)
			(stroke
				(width 0.1)
				(type default)
			)
			(layer "B.Fab")
		)
		(fp_line
			(start -0.120396 0.3048)
			(end -0.120396 0.2794)
			(stroke
				(width 0.1)
				(type default)
			)
			(layer "B.Fab")
		)
		(fp_line
			(start -0.67945 0.3048)
			(end -0.120396 0.3048)
			(stroke
				(width 0.1)
				(type default)
			)
			(layer "B.Fab")
		)
		(pad "1" smd circle
			(at 0.40005 0 270)
			(size 0 0)
			(layers "B.Cu" "B.Mask" "B.Paste")
			(net "BRICK_P12V_1_EN_N")
		)
		(pad "2" smd circle
			(at -0.40005 0 270)
			(size 0 0)
			(layers "B.Cu" "B.Mask" "B.Paste")
			(net "GND")
		)
	)
	(footprint ""
		(layer "B.Cu")
		(at 276.225 -34.29 180)
		(property "Reference" "R5930"
			(at 0 0 0)
			(layer "B.SilkS")
			(hide yes)
			(effects
				(font
					(size 1.27 1.27)
				)
				(justify mirror)
			)
		)
		(property "Value" ""
			(at 0 0 0)
			(layer "B.Fab")
			(effects
				(font
					(size 1.27 1.27)
				)
				(justify mirror)
			)
		)
		(duplicate_pad_numbers_are_jumpers no)
		(fp_line
			(start 1.651 0.8382)
			(end 1.651 -0.8382)
			(stroke
				(width 0.1524)
				(type default)
			)
			(layer "B.SilkS")
		)
		(fp_line
			(start 1.651 -0.8382)
			(end -1.651 -0.8382)
			(stroke
				(width 0.1524)
				(type default)
			)
			(layer "B.SilkS")
		)
		(fp_line
			(start -1.651 0.8382)
			(end 1.651 0.8382)
			(stroke
				(width 0.1524)
				(type default)
			)
			(layer "B.SilkS")
		)
		(fp_line
			(start -1.651 -0.8382)
			(end -1.651 0.8382)
			(stroke
				(width 0.1524)
				(type default)
			)
			(layer "B.SilkS")
		)
		(fp_line
			(start 1.559814 0.7366)
			(end 1.524 0.7366)
			(stroke
				(width 0.1)
				(type default)
			)
			(layer "B.Fab")
		)
		(fp_line
			(start 1.559814 -0.7366)
			(end 1.559814 0.7366)
			(stroke
				(width 0.1)
				(type default)
			)
			(layer "B.Fab")
		)
		(fp_line
			(start 1.524 0.7366)
			(end -1.524 0.7366)
			(stroke
				(width 0.1)
				(type default)
			)
			(layer "B.Fab")
		)
		(fp_line
			(start 1.524 -0.7366)
			(end 1.559814 -0.7366)
			(stroke
				(width 0.1)
				(type default)
			)
			(layer "B.Fab")
		)
		(fp_line
			(start -1.524 0.7366)
			(end -1.560576 0.7366)
			(stroke
				(width 0.1)
				(type default)
			)
			(layer "B.Fab")
		)
		(fp_line
			(start -1.524 -0.7366)
			(end 1.524 -0.7366)
			(stroke
				(width 0.1)
				(type default)
			)
			(layer "B.Fab")
		)
		(fp_line
			(start -1.560576 0.7366)
			(end -1.560576 -0.7366)
			(stroke
				(width 0.1)
				(type default)
			)
			(layer "B.Fab")
		)
		(fp_line
			(start -1.560576 -0.7366)
			(end -1.524 -0.7366)
			(stroke
				(width 0.1)
				(type default)
			)
			(layer "B.Fab")
		)
		(pad "1" smd rect
			(at 0.94996 0 180)
			(size 1.1176 1.3716)
			(layers "B.Cu" "B.Mask" "B.Paste")
			(net "P52V_1_R")
		)
		(pad "2" smd rect
			(at -0.94996 0 180)
			(size 1.1176 1.3716)
			(layers "B.Cu" "B.Mask" "B.Paste")
			(net "P52V_HS1_EN_DELAY_N")
		)
	)
	(footprint ""
		(layer "B.Cu")
		(at 63.881 -76.708 -90)
		(property "Reference" "PR322"
			(at 0 0 90)
			(layer "B.SilkS")
			(hide yes)
			(effects
				(font
					(size 1.27 1.27)
				)
				(justify mirror)
			)
		)
		(property "Value" ""
			(at 0 0 90)
			(layer "B.Fab")
			(effects
				(font
					(size 1.27 1.27)
				)
				(justify mirror)
			)
		)
		(duplicate_pad_numbers_are_jumpers no)
		(fp_line
			(start -0.7874 0.4064)
			(end 0.7874 0.4064)
			(stroke
				(width 0.1524)
				(type default)
			)
			(layer "B.SilkS")
		)
		(fp_line
			(start 0.7874 0.4064)
			(end 0.7874 -0.4064)
			(stroke
				(width 0.1524)
				(type default)
			)
			(layer "B.SilkS")
		)
		(fp_line
			(start -0.7874 -0.4064)
			(end -0.7874 0.4064)
			(stroke
				(width 0.1524)
				(type default)
			)
			(layer "B.SilkS")
		)
		(fp_line
			(start 0.7874 -0.4064)
			(end -0.7874 -0.4064)
			(stroke
				(width 0.1524)
				(type default)
			)
			(layer "B.SilkS")
		)
		(fp_line
			(start -0.67945 0.3048)
			(end -0.120396 0.3048)
			(stroke
				(width 0.1)
				(type default)
			)
			(layer "B.Fab")
		)
		(fp_line
			(start -0.120396 0.3048)
			(end -0.120396 0.2794)
			(stroke
				(width 0.1)
				(type default)
			)
			(layer "B.Fab")
		)
		(fp_line
			(start 0.12065 0.3048)
			(end 0.67945 0.3048)
			(stroke
				(width 0.1)
				(type default)
			)
			(layer "B.Fab")
		)
		(fp_line
			(start 0.67945 0.3048)
			(end 0.67945 -0.305054)
			(stroke
				(width 0.1)
				(type default)
			)
			(layer "B.Fab")
		)
		(fp_line
			(start -0.120396 0.2794)
			(end 0.12065 0.2794)
			(stroke
				(width 0.1)
				(type default)
			)
			(layer "B.Fab")
		)
		(fp_line
			(start 0.12065 0.2794)
			(end 0.12065 0.3048)
			(stroke
				(width 0.1)
				(type default)
			)
			(layer "B.Fab")
		)
		(fp_line
			(start -0.12065 -0.2794)
			(end -0.12065 -0.3048)
			(stroke
				(width 0.1)
				(type default)
			)
			(layer "B.Fab")
		)
		(fp_line
			(start 0.12065 -0.2794)
			(end -0.12065 -0.2794)
			(stroke
				(width 0.1)
				(type default)
			)
			(layer "B.Fab")
		)
		(fp_line
			(start -0.67945 -0.3048)
			(end -0.67945 0.3048)
			(stroke
				(width 0.1)
				(type default)
			)
			(layer "B.Fab")
		)
		(fp_line
			(start -0.12065 -0.3048)
			(end -0.67945 -0.3048)
			(stroke
				(width 0.1)
				(type default)
			)
			(layer "B.Fab")
		)
		(fp_line
			(start 0.12065 -0.305054)
			(end 0.12065 -0.2794)
			(stroke
				(width 0.1)
				(type default)
			)
			(layer "B.Fab")
		)
		(fp_line
			(start 0.67945 -0.305054)
			(end 0.12065 -0.305054)
			(stroke
				(width 0.1)
				(type default)
			)
			(layer "B.Fab")
		)
		(pad "1" smd circle
			(at 0.40005 0 90)
			(size 0 0)
			(layers "B.Cu" "B.Mask" "B.Paste")
			(net "P12V_MB3_SENSE+")
		)
		(pad "2" smd circle
			(at -0.40005 0 90)
			(size 0 0)
			(layers "B.Cu" "B.Mask" "B.Paste")
			(net "P12V_MB2_SENSE+")
		)
	)
)
